(kicad_pcb
	(version 20260206)
	(generator "pcbnew")
	(generator_version "10.0")
	(general
		(thickness 1.6)
		(legacy_teardrops no)
	)
	(paper "A4")
	(title_block
		(title "01162023_DA0F0TEBIF0_F0T_Expander_BD_F_brd_V02_OCP.brd")
		(comment 1 "Grand Teton / footprints 1446-1452 of 9728")
	)
	(layers
		(0 "F.Cu" signal "TOP")
		(4 "In1.Cu" signal "GND")
		(6 "In2.Cu" signal "VCC")
		(8 "In3.Cu" signal "VCC1")
		(10 "In4.Cu" signal "GND1")
		(12 "In5.Cu" signal "IN1")
		(14 "In6.Cu" signal "GND2")
		(16 "In7.Cu" signal "IN2")
		(18 "In8.Cu" signal "GND3")
		(20 "In9.Cu" signal "IN3")
		(22 "In10.Cu" signal "GND4")
		(24 "In11.Cu" signal "IN4")
		(26 "In12.Cu" signal "GND5")
		(28 "In13.Cu" signal "IN5")
		(30 "In14.Cu" signal "GND6")
		(32 "In15.Cu" signal "IN6")
		(34 "In16.Cu" signal "GND7")
		(2 "B.Cu" signal "BOTTOM")
		(9 "F.Adhes" user "F.Adhesive")
		(11 "B.Adhes" user "B.Adhesive")
		(13 "F.Paste" user "Package Geometry/Pastemask Top")
		(15 "B.Paste" user "Package Geometry/Pastemask Bottom")
		(5 "F.SilkS" user "Ref Des/Silkscreen Top")
		(7 "B.SilkS" user "Ref Des/Silkscreen Bottom")
		(1 "F.Mask" user "Board Geometry/Soldermask Top")
		(3 "B.Mask" user "Board Geometry/Soldermask Bottom")
		(17 "Dwgs.User" user "User.Drawings")
		(19 "Cmts.User" user "User.Comments")
		(21 "Eco1.User" user "User.Eco1")
		(23 "Eco2.User" user "User.Eco2")
		(25 "Edge.Cuts" user "Board Geometry/Outline")
		(27 "Margin" user)
		(31 "F.CrtYd" user "Package Geometry/Place Bound Top")
		(29 "B.CrtYd" user "Package Geometry/Place Bound Bottom")
		(35 "F.Fab" user "Ref Des/Assembly Top")
		(33 "B.Fab" user "Ref Des/Assembly Bottom")
	)
	(footprint ""
		(layer "F.Cu")
		(at 338.074 -183.007 180)
		(property "Reference" "R4749"
			(at 0 0 180)
			(layer "F.SilkS")
			(hide yes)
			(effects
				(font
					(size 1.27 1.27)
				)
			)
		)
		(property "Value" ""
			(at 0 0 180)
			(layer "F.Fab")
			(effects
				(font
					(size 1.27 1.27)
				)
			)
		)
		(duplicate_pad_numbers_are_jumpers no)
		(fp_line
			(start 0.7874 0.4064)
			(end -0.7874 0.4064)
			(stroke
				(width 0.1524)
				(type default)
			)
			(layer "F.SilkS")
		)
		(fp_line
			(start 0.7874 -0.4064)
			(end 0.7874 0.4064)
			(stroke
				(width 0.1524)
				(type default)
			)
			(layer "F.SilkS")
		)
		(fp_line
			(start -0.7874 0.4064)
			(end -0.7874 -0.4064)
			(stroke
				(width 0.1524)
				(type default)
			)
			(layer "F.SilkS")
		)
		(fp_line
			(start -0.7874 -0.4064)
			(end 0.7874 -0.4064)
			(stroke
				(width 0.1524)
				(type default)
			)
			(layer "F.SilkS")
		)
		(fp_line
			(start 0.67945 0.3048)
			(end 0.120396 0.3048)
			(stroke
				(width 0.1)
				(type default)
			)
			(layer "F.Fab")
		)
		(fp_line
			(start 0.67945 -0.3048)
			(end 0.67945 0.3048)
			(stroke
				(width 0.1)
				(type default)
			)
			(layer "F.Fab")
		)
		(fp_line
			(start 0.12065 -0.2794)
			(end 0.12065 -0.3048)
			(stroke
				(width 0.1)
				(type default)
			)
			(layer "F.Fab")
		)
		(fp_line
			(start 0.12065 -0.3048)
			(end 0.67945 -0.3048)
			(stroke
				(width 0.1)
				(type default)
			)
			(layer "F.Fab")
		)
		(fp_line
			(start 0.120396 0.3048)
			(end 0.120396 0.2794)
			(stroke
				(width 0.1)
				(type default)
			)
			(layer "F.Fab")
		)
		(fp_line
			(start 0.120396 0.2794)
			(end -0.12065 0.2794)
			(stroke
				(width 0.1)
				(type default)
			)
			(layer "F.Fab")
		)
		(fp_line
			(start -0.12065 0.3048)
			(end -0.67945 0.3048)
			(stroke
				(width 0.1)
				(type default)
			)
			(layer "F.Fab")
		)
		(fp_line
			(start -0.12065 0.2794)
			(end -0.12065 0.3048)
			(stroke
				(width 0.1)
				(type default)
			)
			(layer "F.Fab")
		)
		(fp_line
			(start -0.12065 -0.2794)
			(end 0.12065 -0.2794)
			(stroke
				(width 0.1)
				(type default)
			)
			(layer "F.Fab")
		)
		(fp_line
			(start -0.12065 -0.305054)
			(end -0.12065 -0.2794)
			(stroke
				(width 0.1)
				(type default)
			)
			(layer "F.Fab")
		)
		(fp_line
			(start -0.67945 0.3048)
			(end -0.67945 -0.305054)
			(stroke
				(width 0.1)
				(type default)
			)
			(layer "F.Fab")
		)
		(fp_line
			(start -0.67945 -0.305054)
			(end -0.12065 -0.305054)
			(stroke
				(width 0.1)
				(type default)
			)
			(layer "F.Fab")
		)
		(pad "1" smd circle
			(at -0.40005 0 180)
			(size 0 0)
			(layers "F.Cu" "F.Mask" "F.Paste")
			(net "PRSNT_SSD8_FPGA_PCA9555_N")
		)
		(pad "2" smd circle
			(at 0.40005 0 180)
			(size 0 0)
			(layers "F.Cu" "F.Mask" "F.Paste")
			(net "PRSNT_SSD8_FPGA_R_N")
		)
	)
	(footprint ""
		(layer "F.Cu")
		(at 284.16504 -5.999988)
		(property "Reference" "H62"
			(at -5.272024 -5.20573 0)
			(unlocked yes)
			(layer "F.SilkS")
			(effects
				(font
					(size 0.7874 0.5842)
					(thickness 0.1524)
				)
				(justify left)
			)
		)
		(property "Value" ""
			(at 0 0 0)
			(layer "F.Fab")
			(effects
				(font
					(size 1.27 1.27)
				)
			)
		)
		(duplicate_pad_numbers_are_jumpers no)
		(pad "1" thru_hole circle
			(at 0 0)
			(size 10.0076 10.0076)
			(drill 5.6134)
			(layers "*.Cu" "*.Mask")
			(remove_unused_layers no)
			(net "GND")
			(clearance -1.9431)
		)
	)
	(footprint ""
		(layer "F.Cu")
		(at 426.567854 -54.067456)
		(property "Reference" "PR234"
			(at 0 0 0)
			(layer "F.SilkS")
			(hide yes)
			(effects
				(font
					(size 1.27 1.27)
				)
			)
		)
		(property "Value" ""
			(at 0 0 0)
			(layer "F.Fab")
			(effects
				(font
					(size 1.27 1.27)
				)
			)
		)
		(duplicate_pad_numbers_are_jumpers no)
		(fp_line
			(start -0.7874 -0.4064)
			(end 0.7874 -0.4064)
			(stroke
				(width 0.1524)
				(type default)
			)
			(layer "F.SilkS")
		)
		(fp_line
			(start -0.7874 0.4064)
			(end -0.7874 -0.4064)
			(stroke
				(width 0.1524)
				(type default)
			)
			(layer "F.SilkS")
		)
		(fp_line
			(start 0.7874 -0.4064)
			(end 0.7874 0.4064)
			(stroke
				(width 0.1524)
				(type default)
			)
			(layer "F.SilkS")
		)
		(fp_line
			(start 0.7874 0.4064)
			(end -0.7874 0.4064)
			(stroke
				(width 0.1524)
				(type default)
			)
			(layer "F.SilkS")
		)
		(fp_line
			(start -0.67945 -0.305054)
			(end -0.12065 -0.305054)
			(stroke
				(width 0.1)
				(type default)
			)
			(layer "F.Fab")
		)
		(fp_line
			(start -0.67945 0.3048)
			(end -0.67945 -0.305054)
			(stroke
				(width 0.1)
				(type default)
			)
			(layer "F.Fab")
		)
		(fp_line
			(start -0.12065 -0.305054)
			(end -0.12065 -0.2794)
			(stroke
				(width 0.1)
				(type default)
			)
			(layer "F.Fab")
		)
		(fp_line
			(start -0.12065 -0.2794)
			(end 0.12065 -0.2794)
			(stroke
				(width 0.1)
				(type default)
			)
			(layer "F.Fab")
		)
		(fp_line
			(start -0.12065 0.2794)
			(end -0.12065 0.3048)
			(stroke
				(width 0.1)
				(type default)
			)
			(layer "F.Fab")
		)
		(fp_line
			(start -0.12065 0.3048)
			(end -0.67945 0.3048)
			(stroke
				(width 0.1)
				(type default)
			)
			(layer "F.Fab")
		)
		(fp_line
			(start 0.120396 0.2794)
			(end -0.12065 0.2794)
			(stroke
				(width 0.1)
				(type default)
			)
			(layer "F.Fab")
		)
		(fp_line
			(start 0.120396 0.3048)
			(end 0.120396 0.2794)
			(stroke
				(width 0.1)
				(type default)
			)
			(layer "F.Fab")
		)
		(fp_line
			(start 0.12065 -0.3048)
			(end 0.67945 -0.3048)
			(stroke
				(width 0.1)
				(type default)
			)
			(layer "F.Fab")
		)
		(fp_line
			(start 0.12065 -0.2794)
			(end 0.12065 -0.3048)
			(stroke
				(width 0.1)
				(type default)
			)
			(layer "F.Fab")
		)
		(fp_line
			(start 0.67945 -0.3048)
			(end 0.67945 0.3048)
			(stroke
				(width 0.1)
				(type default)
			)
			(layer "F.Fab")
		)
		(fp_line
			(start 0.67945 0.3048)
			(end 0.120396 0.3048)
			(stroke
				(width 0.1)
				(type default)
			)
			(layer "F.Fab")
		)
		(pad "1" smd circle
			(at -0.40005 0)
			(size 0 0)
			(layers "F.Cu" "F.Mask" "F.Paste")
			(net "P12V_SSD14_OCP")
		)
		(pad "2" smd circle
			(at 0.40005 0)
			(size 0 0)
			(layers "F.Cu" "F.Mask" "F.Paste")
			(net "GND")
		)
	)
	(footprint ""
		(layer "F.Cu")
		(at 365.506 -203.835)
		(property "Reference" "R4685"
			(at 0 0 0)
			(layer "F.SilkS")
			(hide yes)
			(effects
				(font
					(size 1.27 1.27)
				)
			)
		)
		(property "Value" ""
			(at 0 0 0)
			(layer "F.Fab")
			(effects
				(font
					(size 1.27 1.27)
				)
			)
		)
		(duplicate_pad_numbers_are_jumpers no)
		(fp_line
			(start -0.7874 -0.4064)
			(end 0.7874 -0.4064)
			(stroke
				(width 0.1524)
				(type default)
			)
			(layer "F.SilkS")
		)
		(fp_line
			(start -0.7874 0.4064)
			(end -0.7874 -0.4064)
			(stroke
				(width 0.1524)
				(type default)
			)
			(layer "F.SilkS")
		)
		(fp_line
			(start 0.7874 -0.4064)
			(end 0.7874 0.4064)
			(stroke
				(width 0.1524)
				(type default)
			)
			(layer "F.SilkS")
		)
		(fp_line
			(start 0.7874 0.4064)
			(end -0.7874 0.4064)
			(stroke
				(width 0.1524)
				(type default)
			)
			(layer "F.SilkS")
		)
		(fp_line
			(start -0.67945 -0.305054)
			(end -0.12065 -0.305054)
			(stroke
				(width 0.1)
				(type default)
			)
			(layer "F.Fab")
		)
		(fp_line
			(start -0.67945 0.3048)
			(end -0.67945 -0.305054)
			(stroke
				(width 0.1)
				(type default)
			)
			(layer "F.Fab")
		)
		(fp_line
			(start -0.12065 -0.305054)
			(end -0.12065 -0.2794)
			(stroke
				(width 0.1)
				(type default)
			)
			(layer "F.Fab")
		)
		(fp_line
			(start -0.12065 -0.2794)
			(end 0.12065 -0.2794)
			(stroke
				(width 0.1)
				(type default)
			)
			(layer "F.Fab")
		)
		(fp_line
			(start -0.12065 0.2794)
			(end -0.12065 0.3048)
			(stroke
				(width 0.1)
				(type default)
			)
			(layer "F.Fab")
		)
		(fp_line
			(start -0.12065 0.3048)
			(end -0.67945 0.3048)
			(stroke
				(width 0.1)
				(type default)
			)
			(layer "F.Fab")
		)
		(fp_line
			(start 0.120396 0.2794)
			(end -0.12065 0.2794)
			(stroke
				(width 0.1)
				(type default)
			)
			(layer "F.Fab")
		)
		(fp_line
			(start 0.120396 0.3048)
			(end 0.120396 0.2794)
			(stroke
				(width 0.1)
				(type default)
			)
			(layer "F.Fab")
		)
		(fp_line
			(start 0.12065 -0.3048)
			(end 0.67945 -0.3048)
			(stroke
				(width 0.1)
				(type default)
			)
			(layer "F.Fab")
		)
		(fp_line
			(start 0.12065 -0.2794)
			(end 0.12065 -0.3048)
			(stroke
				(width 0.1)
				(type default)
			)
			(layer "F.Fab")
		)
		(fp_line
			(start 0.67945 -0.3048)
			(end 0.67945 0.3048)
			(stroke
				(width 0.1)
				(type default)
			)
			(layer "F.Fab")
		)
		(fp_line
			(start 0.67945 0.3048)
			(end 0.120396 0.3048)
			(stroke
				(width 0.1)
				(type default)
			)
			(layer "F.Fab")
		)
		(pad "1" smd circle
			(at -0.40005 0)
			(size 0 0)
			(layers "F.Cu" "F.Mask" "F.Paste")
			(net "PEX1_PCA9555_0_INT_N")
		)
		(pad "2" smd circle
			(at 0.40005 0)
			(size 0 0)
			(layers "F.Cu" "F.Mask" "F.Paste")
			(net "P1V8_PEX")
		)
	)
	(footprint ""
		(layer "F.Cu")
		(at 329.311 -245.237 90)
		(property "Reference" "R4047"
			(at 0 0 90)
			(layer "F.SilkS")
			(hide yes)
			(effects
				(font
					(size 1.27 1.27)
				)
			)
		)
		(property "Value" ""
			(at 0 0 90)
			(layer "F.Fab")
			(effects
				(font
					(size 1.27 1.27)
				)
			)
		)
		(duplicate_pad_numbers_are_jumpers no)
		(fp_line
			(start 0.7874 -0.4064)
			(end 0.7874 0.4064)
			(stroke
				(width 0.1524)
				(type default)
			)
			(layer "F.SilkS")
		)
		(fp_line
			(start -0.7874 -0.4064)
			(end 0.7874 -0.4064)
			(stroke
				(width 0.1524)
				(type default)
			)
			(layer "F.SilkS")
		)
		(fp_line
			(start 0.7874 0.4064)
			(end -0.7874 0.4064)
			(stroke
				(width 0.1524)
				(type default)
			)
			(layer "F.SilkS")
		)
		(fp_line
			(start -0.7874 0.4064)
			(end -0.7874 -0.4064)
			(stroke
				(width 0.1524)
				(type default)
			)
			(layer "F.SilkS")
		)
		(fp_line
			(start -0.12065 -0.305054)
			(end -0.12065 -0.2794)
			(stroke
				(width 0.1)
				(type default)
			)
			(layer "F.Fab")
		)
		(fp_line
			(start -0.67945 -0.305054)
			(end -0.12065 -0.305054)
			(stroke
				(width 0.1)
				(type default)
			)
			(layer "F.Fab")
		)
		(fp_line
			(start 0.67945 -0.3048)
			(end 0.67945 0.3048)
			(stroke
				(width 0.1)
				(type default)
			)
			(layer "F.Fab")
		)
		(fp_line
			(start 0.12065 -0.3048)
			(end 0.67945 -0.3048)
			(stroke
				(width 0.1)
				(type default)
			)
			(layer "F.Fab")
		)
		(fp_line
			(start 0.12065 -0.2794)
			(end 0.12065 -0.3048)
			(stroke
				(width 0.1)
				(type default)
			)
			(layer "F.Fab")
		)
		(fp_line
			(start -0.12065 -0.2794)
			(end 0.12065 -0.2794)
			(stroke
				(width 0.1)
				(type default)
			)
			(layer "F.Fab")
		)
		(fp_line
			(start 0.120396 0.2794)
			(end -0.12065 0.2794)
			(stroke
				(width 0.1)
				(type default)
			)
			(layer "F.Fab")
		)
		(fp_line
			(start -0.12065 0.2794)
			(end -0.12065 0.3048)
			(stroke
				(width 0.1)
				(type default)
			)
			(layer "F.Fab")
		)
		(fp_line
			(start 0.67945 0.3048)
			(end 0.120396 0.3048)
			(stroke
				(width 0.1)
				(type default)
			)
			(layer "F.Fab")
		)
		(fp_line
			(start 0.120396 0.3048)
			(end 0.120396 0.2794)
			(stroke
				(width 0.1)
				(type default)
			)
			(layer "F.Fab")
		)
		(fp_line
			(start -0.12065 0.3048)
			(end -0.67945 0.3048)
			(stroke
				(width 0.1)
				(type default)
			)
			(layer "F.Fab")
		)
		(fp_line
			(start -0.67945 0.3048)
			(end -0.67945 -0.305054)
			(stroke
				(width 0.1)
				(type default)
			)
			(layer "F.Fab")
		)
		(pad "1" smd circle
			(at -0.40005 0 90)
			(size 0 0)
			(layers "F.Cu" "F.Mask" "F.Paste")
			(net "P3V3_AUX")
		)
		(pad "2" smd circle
			(at 0.40005 0 90)
			(size 0 0)
			(layers "F.Cu" "F.Mask" "F.Paste")
			(net "JP_FPGA_FRC_PWRON_N")
		)
	)
	(footprint ""
		(layer "F.Cu")
		(at 363.478826 -111.377476 -90)
		(property "Reference" "PR7103"
			(at 0 0 270)
			(layer "F.SilkS")
			(hide yes)
			(effects
				(font
					(size 1.27 1.27)
				)
			)
		)
		(property "Value" ""
			(at 0 0 270)
			(layer "F.Fab")
			(effects
				(font
					(size 1.27 1.27)
				)
			)
		)
		(duplicate_pad_numbers_are_jumpers no)
		(fp_line
			(start -0.7874 0.4064)
			(end -0.7874 -0.4064)
			(stroke
				(width 0.1524)
				(type default)
			)
			(layer "F.SilkS")
		)
		(fp_line
			(start 0.7874 0.4064)
			(end -0.7874 0.4064)
			(stroke
				(width 0.1524)
				(type default)
			)
			(layer "F.SilkS")
		)
		(fp_line
			(start -0.7874 -0.4064)
			(end 0.7874 -0.4064)
			(stroke
				(width 0.1524)
				(type default)
			)
			(layer "F.SilkS")
		)
		(fp_line
			(start 0.7874 -0.4064)
			(end 0.7874 0.4064)
			(stroke
				(width 0.1524)
				(type default)
			)
			(layer "F.SilkS")
		)
		(fp_line
			(start -0.67945 0.3048)
			(end -0.67945 -0.305054)
			(stroke
				(width 0.1)
				(type default)
			)
			(layer "F.Fab")
		)
		(fp_line
			(start -0.12065 0.3048)
			(end -0.67945 0.3048)
			(stroke
				(width 0.1)
				(type default)
			)
			(layer "F.Fab")
		)
		(fp_line
			(start 0.120396 0.3048)
			(end 0.120396 0.2794)
			(stroke
				(width 0.1)
				(type default)
			)
			(layer "F.Fab")
		)
		(fp_line
			(start 0.67945 0.3048)
			(end 0.120396 0.3048)
			(stroke
				(width 0.1)
				(type default)
			)
			(layer "F.Fab")
		)
		(fp_line
			(start -0.12065 0.2794)
			(end -0.12065 0.3048)
			(stroke
				(width 0.1)
				(type default)
			)
			(layer "F.Fab")
		)
		(fp_line
			(start 0.120396 0.2794)
			(end -0.12065 0.2794)
			(stroke
				(width 0.1)
				(type default)
			)
			(layer "F.Fab")
		)
		(fp_line
			(start -0.12065 -0.2794)
			(end 0.12065 -0.2794)
			(stroke
				(width 0.1)
				(type default)
			)
			(layer "F.Fab")
		)
		(fp_line
			(start 0.12065 -0.2794)
			(end 0.12065 -0.3048)
			(stroke
				(width 0.1)
				(type default)
			)
			(layer "F.Fab")
		)
		(fp_line
			(start 0.12065 -0.3048)
			(end 0.67945 -0.3048)
			(stroke
				(width 0.1)
				(type default)
			)
			(layer "F.Fab")
		)
		(fp_line
			(start 0.67945 -0.3048)
			(end 0.67945 0.3048)
			(stroke
				(width 0.1)
				(type default)
			)
			(layer "F.Fab")
		)
		(fp_line
			(start -0.67945 -0.305054)
			(end -0.12065 -0.305054)
			(stroke
				(width 0.1)
				(type default)
			)
			(layer "F.Fab")
		)
		(fp_line
			(start -0.12065 -0.305054)
			(end -0.12065 -0.2794)
			(stroke
				(width 0.1)
				(type default)
			)
			(layer "F.Fab")
		)
		(pad "1" smd circle
			(at -0.40005 0 270)
			(size 0 0)
			(layers "F.Cu" "F.Mask" "F.Paste")
			(net "P3V3_NIC6_CO_MODE")
		)
		(pad "2" smd circle
			(at 0.40005 0 270)
			(size 0 0)
			(layers "F.Cu" "F.Mask" "F.Paste")
			(net "GND")
		)
	)
	(footprint ""
		(layer "F.Cu")
		(at 177.593752 -165.670484 -90)
		(property "Reference" "R2465"
			(at 0 0 270)
			(layer "F.SilkS")
			(hide yes)
			(effects
				(font
					(size 1.27 1.27)
				)
			)
		)
		(property "Value" ""
			(at 0 0 270)
			(layer "F.Fab")
			(effects
				(font
					(size 1.27 1.27)
				)
			)
		)
		(duplicate_pad_numbers_are_jumpers no)
		(fp_line
			(start -0.7874 0.4064)
			(end -0.7874 -0.4064)
			(stroke
				(width 0.1524)
				(type default)
			)
			(layer "F.SilkS")
		)
		(fp_line
			(start 0.7874 0.4064)
			(end -0.7874 0.4064)
			(stroke
				(width 0.1524)
				(type default)
			)
			(layer "F.SilkS")
		)
		(fp_line
			(start -0.7874 -0.4064)
			(end 0.7874 -0.4064)
			(stroke
				(width 0.1524)
				(type default)
			)
			(layer "F.SilkS")
		)
		(fp_line
			(start 0.7874 -0.4064)
			(end 0.7874 0.4064)
			(stroke
				(width 0.1524)
				(type default)
			)
			(layer "F.SilkS")
		)
		(fp_line
			(start -0.67945 0.3048)
			(end -0.67945 -0.305054)
			(stroke
				(width 0.1)
				(type default)
			)
			(layer "F.Fab")
		)
		(fp_line
			(start -0.12065 0.3048)
			(end -0.67945 0.3048)
			(stroke
				(width 0.1)
				(type default)
			)
			(layer "F.Fab")
		)
		(fp_line
			(start 0.120396 0.3048)
			(end 0.120396 0.2794)
			(stroke
				(width 0.1)
				(type default)
			)
			(layer "F.Fab")
		)
		(fp_line
			(start 0.67945 0.3048)
			(end 0.120396 0.3048)
			(stroke
				(width 0.1)
				(type default)
			)
			(layer "F.Fab")
		)
		(fp_line
			(start -0.12065 0.2794)
			(end -0.12065 0.3048)
			(stroke
				(width 0.1)
				(type default)
			)
			(layer "F.Fab")
		)
		(fp_line
			(start 0.120396 0.2794)
			(end -0.12065 0.2794)
			(stroke
				(width 0.1)
				(type default)
			)
			(layer "F.Fab")
		)
		(fp_line
			(start -0.12065 -0.2794)
			(end 0.12065 -0.2794)
			(stroke
				(width 0.1)
				(type default)
			)
			(layer "F.Fab")
		)
		(fp_line
			(start 0.12065 -0.2794)
			(end 0.12065 -0.3048)
			(stroke
				(width 0.1)
				(type default)
			)
			(layer "F.Fab")
		)
		(fp_line
			(start 0.12065 -0.3048)
			(end 0.67945 -0.3048)
			(stroke
				(width 0.1)
				(type default)
			)
			(layer "F.Fab")
		)
		(fp_line
			(start 0.67945 -0.3048)
			(end 0.67945 0.3048)
			(stroke
				(width 0.1)
				(type default)
			)
			(layer "F.Fab")
		)
		(fp_line
			(start -0.67945 -0.305054)
			(end -0.12065 -0.305054)
			(stroke
				(width 0.1)
				(type default)
			)
			(layer "F.Fab")
		)
		(fp_line
			(start -0.12065 -0.305054)
			(end -0.12065 -0.2794)
			(stroke
				(width 0.1)
				(type default)
			)
			(layer "F.Fab")
		)
		(pad "1" smd circle
			(at -0.40005 0 270)
			(size 0 0)
			(layers "F.Cu" "F.Mask" "F.Paste")
			(net "P3V3_NIC2")
		)
		(pad "2" smd circle
			(at 0.40005 0 270)
			(size 0 0)
			(layers "F.Cu" "F.Mask" "F.Paste")
			(net "NIC2_PWRBRK_N")
		)
	)
)
